(kicad_pcb
	(version 20260206)
	(generator "pcbnew")
	(generator_version "10.0")
	(general
		(thickness 1.6)
		(legacy_teardrops no)
	)
	(paper "A4")
	(title_block
		(title "03242023_DA0F0TMBIJ0_F0T_Motherboard_J_brd_V01_OCP.brd")
		(comment 1 "Grand Teton / footprints 2558-2564 of 6105")
	)
	(layers
		(0 "F.Cu" signal "TOP")
		(4 "In1.Cu" signal "GND")
		(6 "In2.Cu" signal "IN1")
		(8 "In3.Cu" signal "GND1")
		(10 "In4.Cu" signal "IN2")
		(12 "In5.Cu" signal "GND2")
		(14 "In6.Cu" signal "IN3")
		(16 "In7.Cu" signal "GND3")
		(18 "In8.Cu" signal "VCC")
		(20 "In9.Cu" signal "VCC1")
		(22 "In10.Cu" signal "GND4")
		(24 "In11.Cu" signal "IN4")
		(26 "In12.Cu" signal "GND5")
		(28 "In13.Cu" signal "IN5")
		(30 "In14.Cu" signal "GND6")
		(32 "In15.Cu" signal "IN6")
		(34 "In16.Cu" signal "GND7")
		(2 "B.Cu" signal "BOTTOM")
		(9 "F.Adhes" user "F.Adhesive")
		(11 "B.Adhes" user "B.Adhesive")
		(13 "F.Paste" user "Package Geometry/Pastemask Top")
		(15 "B.Paste" user "Package Geometry/Pastemask Bottom")
		(5 "F.SilkS" user "Ref Des/Silkscreen Top")
		(7 "B.SilkS" user "Ref Des/Silkscreen Bottom")
		(1 "F.Mask" user "Board Geometry/Soldermask Top")
		(3 "B.Mask" user "Board Geometry/Soldermask Bottom")
		(17 "Dwgs.User" user "User.Drawings")
		(19 "Cmts.User" user "User.Comments")
		(21 "Eco1.User" user "User.Eco1")
		(23 "Eco2.User" user "User.Eco2")
		(25 "Edge.Cuts" user "Board Geometry/Outline")
		(27 "Margin" user)
		(31 "F.CrtYd" user "Package Geometry/Place Bound Top")
		(29 "B.CrtYd" user "Package Geometry/Place Bound Bottom")
		(35 "F.Fab" user "Ref Des/Assembly Top")
		(33 "B.Fab" user "Ref Des/Assembly Bottom")
	)
	(footprint ""
		(layer "F.Cu")
		(at 372.83136 -413.918908 -90)
		(property "Reference" "R3033"
			(at 0 0 270)
			(layer "F.SilkS")
			(hide yes)
			(effects
				(font
					(size 1.27 1.27)
				)
			)
		)
		(property "Value" ""
			(at 0 0 270)
			(layer "F.Fab")
			(effects
				(font
					(size 1.27 1.27)
				)
			)
		)
		(duplicate_pad_numbers_are_jumpers no)
		(fp_line
			(start -0.7874 0.4064)
			(end -0.7874 -0.4064)
			(stroke
				(width 0.1524)
				(type default)
			)
			(layer "F.SilkS")
		)
		(fp_line
			(start 0.7874 0.4064)
			(end -0.7874 0.4064)
			(stroke
				(width 0.1524)
				(type default)
			)
			(layer "F.SilkS")
		)
		(fp_line
			(start -0.7874 -0.4064)
			(end 0.7874 -0.4064)
			(stroke
				(width 0.1524)
				(type default)
			)
			(layer "F.SilkS")
		)
		(fp_line
			(start 0.7874 -0.4064)
			(end 0.7874 0.4064)
			(stroke
				(width 0.1524)
				(type default)
			)
			(layer "F.SilkS")
		)
		(fp_line
			(start -0.67945 0.3048)
			(end -0.67945 -0.305054)
			(stroke
				(width 0.1)
				(type default)
			)
			(layer "F.Fab")
		)
		(fp_line
			(start -0.12065 0.3048)
			(end -0.67945 0.3048)
			(stroke
				(width 0.1)
				(type default)
			)
			(layer "F.Fab")
		)
		(fp_line
			(start 0.120396 0.3048)
			(end 0.120396 0.2794)
			(stroke
				(width 0.1)
				(type default)
			)
			(layer "F.Fab")
		)
		(fp_line
			(start 0.67945 0.3048)
			(end 0.120396 0.3048)
			(stroke
				(width 0.1)
				(type default)
			)
			(layer "F.Fab")
		)
		(fp_line
			(start -0.12065 0.2794)
			(end -0.12065 0.3048)
			(stroke
				(width 0.1)
				(type default)
			)
			(layer "F.Fab")
		)
		(fp_line
			(start 0.120396 0.2794)
			(end -0.12065 0.2794)
			(stroke
				(width 0.1)
				(type default)
			)
			(layer "F.Fab")
		)
		(fp_line
			(start -0.12065 -0.2794)
			(end 0.12065 -0.2794)
			(stroke
				(width 0.1)
				(type default)
			)
			(layer "F.Fab")
		)
		(fp_line
			(start 0.12065 -0.2794)
			(end 0.12065 -0.3048)
			(stroke
				(width 0.1)
				(type default)
			)
			(layer "F.Fab")
		)
		(fp_line
			(start 0.12065 -0.3048)
			(end 0.67945 -0.3048)
			(stroke
				(width 0.1)
				(type default)
			)
			(layer "F.Fab")
		)
		(fp_line
			(start 0.67945 -0.3048)
			(end 0.67945 0.3048)
			(stroke
				(width 0.1)
				(type default)
			)
			(layer "F.Fab")
		)
		(fp_line
			(start -0.67945 -0.305054)
			(end -0.12065 -0.305054)
			(stroke
				(width 0.1)
				(type default)
			)
			(layer "F.Fab")
		)
		(fp_line
			(start -0.12065 -0.305054)
			(end -0.12065 -0.2794)
			(stroke
				(width 0.1)
				(type default)
			)
			(layer "F.Fab")
		)
		(pad "1" smd circle
			(at -0.40005 0 270)
			(size 0 0)
			(layers "F.Cu" "F.Mask" "F.Paste")
			(net "UART_BMC_BIC_RX")
		)
		(pad "2" smd circle
			(at 0.40005 0 270)
			(size 0 0)
			(layers "F.Cu" "F.Mask" "F.Paste")
			(net "UART_BMC_BIC_R_RX")
		)
	)
	(footprint ""
		(layer "F.Cu")
		(at 390.69137 -402.371052 -90)
		(property "Reference" "C946"
			(at 0 0 270)
			(layer "F.SilkS")
			(hide yes)
			(effects
				(font
					(size 1.27 1.27)
				)
			)
		)
		(property "Value" ""
			(at 0 0 270)
			(layer "F.Fab")
			(effects
				(font
					(size 1.27 1.27)
				)
			)
		)
		(duplicate_pad_numbers_are_jumpers no)
		(fp_line
			(start -0.299974 0.150114)
			(end -0.299974 -0.150114)
			(stroke
				(width 0.1)
				(type default)
			)
			(layer "F.Fab")
		)
		(fp_line
			(start 0.299974 0.150114)
			(end -0.299974 0.150114)
			(stroke
				(width 0.1)
				(type default)
			)
			(layer "F.Fab")
		)
		(fp_line
			(start -0.299974 -0.150114)
			(end 0.299974 -0.150114)
			(stroke
				(width 0.1)
				(type default)
			)
			(layer "F.Fab")
		)
		(fp_line
			(start 0.299974 -0.150114)
			(end 0.299974 0.150114)
			(stroke
				(width 0.1)
				(type default)
			)
			(layer "F.Fab")
		)
		(pad "1" smd rect
			(at -0.2667 0 270)
			(size 0.3048 0.381)
			(layers "F.Cu" "F.Mask" "F.Paste")
			(net "P5E_CPU0_PE2_TX_C_DN<9>")
		)
		(pad "2" smd rect
			(at 0.2667 0 270)
			(size 0.3048 0.381)
			(layers "F.Cu" "F.Mask" "F.Paste")
			(net "P5E_CPU0_PE2_TX_DN<9>")
		)
	)
	(footprint ""
		(layer "F.Cu")
		(at 164.64788 -115.026948)
		(property "Reference" "R2346"
			(at 0 0 0)
			(layer "F.SilkS")
			(hide yes)
			(effects
				(font
					(size 1.27 1.27)
				)
			)
		)
		(property "Value" ""
			(at 0 0 0)
			(layer "F.Fab")
			(effects
				(font
					(size 1.27 1.27)
				)
			)
		)
		(duplicate_pad_numbers_are_jumpers no)
		(fp_line
			(start -0.7874 -0.4064)
			(end 0.7874 -0.4064)
			(stroke
				(width 0.1524)
				(type default)
			)
			(layer "F.SilkS")
		)
		(fp_line
			(start -0.7874 0.4064)
			(end -0.7874 -0.4064)
			(stroke
				(width 0.1524)
				(type default)
			)
			(layer "F.SilkS")
		)
		(fp_line
			(start 0.7874 -0.4064)
			(end 0.7874 0.4064)
			(stroke
				(width 0.1524)
				(type default)
			)
			(layer "F.SilkS")
		)
		(fp_line
			(start 0.7874 0.4064)
			(end -0.7874 0.4064)
			(stroke
				(width 0.1524)
				(type default)
			)
			(layer "F.SilkS")
		)
		(fp_line
			(start -0.67945 -0.305054)
			(end -0.12065 -0.305054)
			(stroke
				(width 0.1)
				(type default)
			)
			(layer "F.Fab")
		)
		(fp_line
			(start -0.67945 0.3048)
			(end -0.67945 -0.305054)
			(stroke
				(width 0.1)
				(type default)
			)
			(layer "F.Fab")
		)
		(fp_line
			(start -0.12065 -0.305054)
			(end -0.12065 -0.2794)
			(stroke
				(width 0.1)
				(type default)
			)
			(layer "F.Fab")
		)
		(fp_line
			(start -0.12065 -0.2794)
			(end 0.12065 -0.2794)
			(stroke
				(width 0.1)
				(type default)
			)
			(layer "F.Fab")
		)
		(fp_line
			(start -0.12065 0.2794)
			(end -0.12065 0.3048)
			(stroke
				(width 0.1)
				(type default)
			)
			(layer "F.Fab")
		)
		(fp_line
			(start -0.12065 0.3048)
			(end -0.67945 0.3048)
			(stroke
				(width 0.1)
				(type default)
			)
			(layer "F.Fab")
		)
		(fp_line
			(start 0.120396 0.2794)
			(end -0.12065 0.2794)
			(stroke
				(width 0.1)
				(type default)
			)
			(layer "F.Fab")
		)
		(fp_line
			(start 0.120396 0.3048)
			(end 0.120396 0.2794)
			(stroke
				(width 0.1)
				(type default)
			)
			(layer "F.Fab")
		)
		(fp_line
			(start 0.12065 -0.3048)
			(end 0.67945 -0.3048)
			(stroke
				(width 0.1)
				(type default)
			)
			(layer "F.Fab")
		)
		(fp_line
			(start 0.12065 -0.2794)
			(end 0.12065 -0.3048)
			(stroke
				(width 0.1)
				(type default)
			)
			(layer "F.Fab")
		)
		(fp_line
			(start 0.67945 -0.3048)
			(end 0.67945 0.3048)
			(stroke
				(width 0.1)
				(type default)
			)
			(layer "F.Fab")
		)
		(fp_line
			(start 0.67945 0.3048)
			(end 0.120396 0.3048)
			(stroke
				(width 0.1)
				(type default)
			)
			(layer "F.Fab")
		)
		(pad "1" smd circle
			(at -0.40005 0)
			(size 0 0)
			(layers "F.Cu" "F.Mask" "F.Paste")
			(net "P3V3_AUX")
		)
		(pad "2" smd circle
			(at 0.40005 0)
			(size 0 0)
			(layers "F.Cu" "F.Mask" "F.Paste")
			(net "PWRGD_P5V_AUX_R2")
		)
	)
	(footprint ""
		(layer "F.Cu")
		(at 452.482712 -74.136504)
		(property "Reference" "PC568"
			(at 0 0 0)
			(layer "F.SilkS")
			(hide yes)
			(effects
				(font
					(size 1.27 1.27)
				)
			)
		)
		(property "Value" ""
			(at 0 0 0)
			(layer "F.Fab")
			(effects
				(font
					(size 1.27 1.27)
				)
			)
		)
		(duplicate_pad_numbers_are_jumpers no)
		(fp_line
			(start -0.7874 -0.4064)
			(end 0.7874 -0.4064)
			(stroke
				(width 0.1524)
				(type default)
			)
			(layer "F.SilkS")
		)
		(fp_line
			(start -0.7874 0.4064)
			(end -0.7874 -0.4064)
			(stroke
				(width 0.1524)
				(type default)
			)
			(layer "F.SilkS")
		)
		(fp_line
			(start 0.7874 -0.4064)
			(end 0.7874 0.4064)
			(stroke
				(width 0.1524)
				(type default)
			)
			(layer "F.SilkS")
		)
		(fp_line
			(start 0.7874 0.4064)
			(end -0.7874 0.4064)
			(stroke
				(width 0.1524)
				(type default)
			)
			(layer "F.SilkS")
		)
		(fp_line
			(start -0.67945 -0.305054)
			(end -0.12065 -0.305054)
			(stroke
				(width 0.1)
				(type default)
			)
			(layer "F.Fab")
		)
		(fp_line
			(start -0.67945 0.3048)
			(end -0.67945 -0.305054)
			(stroke
				(width 0.1)
				(type default)
			)
			(layer "F.Fab")
		)
		(fp_line
			(start -0.12065 -0.305054)
			(end -0.12065 -0.2794)
			(stroke
				(width 0.1)
				(type default)
			)
			(layer "F.Fab")
		)
		(fp_line
			(start -0.12065 -0.2794)
			(end 0.12065 -0.2794)
			(stroke
				(width 0.1)
				(type default)
			)
			(layer "F.Fab")
		)
		(fp_line
			(start -0.12065 0.2794)
			(end -0.12065 0.3048)
			(stroke
				(width 0.1)
				(type default)
			)
			(layer "F.Fab")
		)
		(fp_line
			(start -0.12065 0.3048)
			(end -0.67945 0.3048)
			(stroke
				(width 0.1)
				(type default)
			)
			(layer "F.Fab")
		)
		(fp_line
			(start 0.120396 0.2794)
			(end -0.12065 0.2794)
			(stroke
				(width 0.1)
				(type default)
			)
			(layer "F.Fab")
		)
		(fp_line
			(start 0.120396 0.3048)
			(end 0.120396 0.2794)
			(stroke
				(width 0.1)
				(type default)
			)
			(layer "F.Fab")
		)
		(fp_line
			(start 0.12065 -0.3048)
			(end 0.67945 -0.3048)
			(stroke
				(width 0.1)
				(type default)
			)
			(layer "F.Fab")
		)
		(fp_line
			(start 0.12065 -0.2794)
			(end 0.12065 -0.3048)
			(stroke
				(width 0.1)
				(type default)
			)
			(layer "F.Fab")
		)
		(fp_line
			(start 0.67945 -0.3048)
			(end 0.67945 0.3048)
			(stroke
				(width 0.1)
				(type default)
			)
			(layer "F.Fab")
		)
		(fp_line
			(start 0.67945 0.3048)
			(end 0.120396 0.3048)
			(stroke
				(width 0.1)
				(type default)
			)
			(layer "F.Fab")
		)
		(pad "1" smd circle
			(at -0.40005 0)
			(size 0 0)
			(layers "F.Cu" "F.Mask" "F.Paste")
			(net "SW_P3V3_AUX_BOOTR")
		)
		(pad "2" smd circle
			(at 0.40005 0)
			(size 0 0)
			(layers "F.Cu" "F.Mask" "F.Paste")
			(net "SW_P3V3_AUX_BOOT_R")
		)
	)
	(footprint ""
		(layer "F.Cu")
		(at 157.02788 -121.376948 180)
		(property "Reference" "R981"
			(at 0 0 180)
			(layer "F.SilkS")
			(hide yes)
			(effects
				(font
					(size 1.27 1.27)
				)
			)
		)
		(property "Value" ""
			(at 0 0 180)
			(layer "F.Fab")
			(effects
				(font
					(size 1.27 1.27)
				)
			)
		)
		(duplicate_pad_numbers_are_jumpers no)
		(fp_line
			(start 0.7874 0.4064)
			(end -0.7874 0.4064)
			(stroke
				(width 0.1524)
				(type default)
			)
			(layer "F.SilkS")
		)
		(fp_line
			(start 0.7874 -0.4064)
			(end 0.7874 0.4064)
			(stroke
				(width 0.1524)
				(type default)
			)
			(layer "F.SilkS")
		)
		(fp_line
			(start -0.7874 0.4064)
			(end -0.7874 -0.4064)
			(stroke
				(width 0.1524)
				(type default)
			)
			(layer "F.SilkS")
		)
		(fp_line
			(start -0.7874 -0.4064)
			(end 0.7874 -0.4064)
			(stroke
				(width 0.1524)
				(type default)
			)
			(layer "F.SilkS")
		)
		(fp_line
			(start 0.67945 0.3048)
			(end 0.120396 0.3048)
			(stroke
				(width 0.1)
				(type default)
			)
			(layer "F.Fab")
		)
		(fp_line
			(start 0.67945 -0.3048)
			(end 0.67945 0.3048)
			(stroke
				(width 0.1)
				(type default)
			)
			(layer "F.Fab")
		)
		(fp_line
			(start 0.12065 -0.2794)
			(end 0.12065 -0.3048)
			(stroke
				(width 0.1)
				(type default)
			)
			(layer "F.Fab")
		)
		(fp_line
			(start 0.12065 -0.3048)
			(end 0.67945 -0.3048)
			(stroke
				(width 0.1)
				(type default)
			)
			(layer "F.Fab")
		)
		(fp_line
			(start 0.120396 0.3048)
			(end 0.120396 0.2794)
			(stroke
				(width 0.1)
				(type default)
			)
			(layer "F.Fab")
		)
		(fp_line
			(start 0.120396 0.2794)
			(end -0.12065 0.2794)
			(stroke
				(width 0.1)
				(type default)
			)
			(layer "F.Fab")
		)
		(fp_line
			(start -0.12065 0.3048)
			(end -0.67945 0.3048)
			(stroke
				(width 0.1)
				(type default)
			)
			(layer "F.Fab")
		)
		(fp_line
			(start -0.12065 0.2794)
			(end -0.12065 0.3048)
			(stroke
				(width 0.1)
				(type default)
			)
			(layer "F.Fab")
		)
		(fp_line
			(start -0.12065 -0.2794)
			(end 0.12065 -0.2794)
			(stroke
				(width 0.1)
				(type default)
			)
			(layer "F.Fab")
		)
		(fp_line
			(start -0.12065 -0.305054)
			(end -0.12065 -0.2794)
			(stroke
				(width 0.1)
				(type default)
			)
			(layer "F.Fab")
		)
		(fp_line
			(start -0.67945 0.3048)
			(end -0.67945 -0.305054)
			(stroke
				(width 0.1)
				(type default)
			)
			(layer "F.Fab")
		)
		(fp_line
			(start -0.67945 -0.305054)
			(end -0.12065 -0.305054)
			(stroke
				(width 0.1)
				(type default)
			)
			(layer "F.Fab")
		)
		(pad "1" smd circle
			(at -0.40005 0 180)
			(size 0 0)
			(layers "F.Cu" "F.Mask" "F.Paste")
			(net "FM_PVCCIN_CPU0_R_EN")
		)
		(pad "2" smd circle
			(at 0.40005 0 180)
			(size 0 0)
			(layers "F.Cu" "F.Mask" "F.Paste")
			(net "FM_PVCCIN_CPU0_EN")
		)
	)
	(footprint ""
		(layer "F.Cu")
		(at 40.627554 -106.015282)
		(property "Reference" "R3687"
			(at 0 0 0)
			(layer "F.SilkS")
			(hide yes)
			(effects
				(font
					(size 1.27 1.27)
				)
			)
		)
		(property "Value" ""
			(at 0 0 0)
			(layer "F.Fab")
			(effects
				(font
					(size 1.27 1.27)
				)
			)
		)
		(duplicate_pad_numbers_are_jumpers no)
		(fp_line
			(start -0.7874 -0.4064)
			(end 0.7874 -0.4064)
			(stroke
				(width 0.1524)
				(type default)
			)
			(layer "F.SilkS")
		)
		(fp_line
			(start -0.7874 0.4064)
			(end -0.7874 -0.4064)
			(stroke
				(width 0.1524)
				(type default)
			)
			(layer "F.SilkS")
		)
		(fp_line
			(start 0.7874 -0.4064)
			(end 0.7874 0.4064)
			(stroke
				(width 0.1524)
				(type default)
			)
			(layer "F.SilkS")
		)
		(fp_line
			(start 0.7874 0.4064)
			(end -0.7874 0.4064)
			(stroke
				(width 0.1524)
				(type default)
			)
			(layer "F.SilkS")
		)
		(fp_line
			(start -0.67945 -0.305054)
			(end -0.12065 -0.305054)
			(stroke
				(width 0.1)
				(type default)
			)
			(layer "F.Fab")
		)
		(fp_line
			(start -0.67945 0.3048)
			(end -0.67945 -0.305054)
			(stroke
				(width 0.1)
				(type default)
			)
			(layer "F.Fab")
		)
		(fp_line
			(start -0.12065 -0.305054)
			(end -0.12065 -0.2794)
			(stroke
				(width 0.1)
				(type default)
			)
			(layer "F.Fab")
		)
		(fp_line
			(start -0.12065 -0.2794)
			(end 0.12065 -0.2794)
			(stroke
				(width 0.1)
				(type default)
			)
			(layer "F.Fab")
		)
		(fp_line
			(start -0.12065 0.2794)
			(end -0.12065 0.3048)
			(stroke
				(width 0.1)
				(type default)
			)
			(layer "F.Fab")
		)
		(fp_line
			(start -0.12065 0.3048)
			(end -0.67945 0.3048)
			(stroke
				(width 0.1)
				(type default)
			)
			(layer "F.Fab")
		)
		(fp_line
			(start 0.120396 0.2794)
			(end -0.12065 0.2794)
			(stroke
				(width 0.1)
				(type default)
			)
			(layer "F.Fab")
		)
		(fp_line
			(start 0.120396 0.3048)
			(end 0.120396 0.2794)
			(stroke
				(width 0.1)
				(type default)
			)
			(layer "F.Fab")
		)
		(fp_line
			(start 0.12065 -0.3048)
			(end 0.67945 -0.3048)
			(stroke
				(width 0.1)
				(type default)
			)
			(layer "F.Fab")
		)
		(fp_line
			(start 0.12065 -0.2794)
			(end 0.12065 -0.3048)
			(stroke
				(width 0.1)
				(type default)
			)
			(layer "F.Fab")
		)
		(fp_line
			(start 0.67945 -0.3048)
			(end 0.67945 0.3048)
			(stroke
				(width 0.1)
				(type default)
			)
			(layer "F.Fab")
		)
		(fp_line
			(start 0.67945 0.3048)
			(end 0.120396 0.3048)
			(stroke
				(width 0.1)
				(type default)
			)
			(layer "F.Fab")
		)
		(pad "1" smd rect
			(at -0.40005 0 180)
			(size 0.4572 0.508)
			(layers "F.Cu" "F.Mask" "F.Paste")
			(net "P1V581_PDB_ADC")
		)
		(pad "2" smd rect
			(at 0.40005 0 180)
			(size 0.4572 0.508)
			(layers "F.Cu" "F.Mask" "F.Paste")
			(net "P3V3_PDB_AUX_ADC_MAM")
		)
	)
	(footprint ""
		(layer "F.Cu")
		(at 64.614298 -24.798782 180)
		(property "Reference" "PC1320"
			(at 0 0 180)
			(layer "F.SilkS")
			(hide yes)
			(effects
				(font
					(size 1.27 1.27)
				)
			)
		)
		(property "Value" ""
			(at 0 0 180)
			(layer "F.Fab")
			(effects
				(font
					(size 1.27 1.27)
				)
			)
		)
		(duplicate_pad_numbers_are_jumpers no)
		(fp_line
			(start 1.2954 0.5842)
			(end -1.2954 0.5842)
			(stroke
				(width 0.1524)
				(type default)
			)
			(layer "F.SilkS")
		)
		(fp_line
			(start 1.2954 -0.5842)
			(end 1.2954 0.5842)
			(stroke
				(width 0.1524)
				(type default)
			)
			(layer "F.SilkS")
		)
		(fp_line
			(start 0 -0.5842)
			(end 0 0.5842)
			(stroke
				(width 0.1524)
				(type default)
			)
			(layer "F.SilkS")
		)
		(fp_line
			(start -1.2954 0.5842)
			(end -1.2954 -0.5842)
			(stroke
				(width 0.1524)
				(type default)
			)
			(layer "F.SilkS")
		)
		(fp_line
			(start -1.2954 -0.5842)
			(end 1.2954 -0.5842)
			(stroke
				(width 0.1524)
				(type default)
			)
			(layer "F.SilkS")
		)
		(fp_line
			(start 1.1938 0.4064)
			(end 0.8636 0.4064)
			(stroke
				(width 0.1)
				(type default)
			)
			(layer "F.Fab")
		)
		(fp_line
			(start 1.1938 -0.4064)
			(end 1.1938 0.4064)
			(stroke
				(width 0.1)
				(type default)
			)
			(layer "F.Fab")
		)
		(fp_line
			(start 0.8636 0.4572)
			(end -0.8636 0.4572)
			(stroke
				(width 0.1)
				(type default)
			)
			(layer "F.Fab")
		)
		(fp_line
			(start 0.8636 0.4064)
			(end 0.8636 0.4572)
			(stroke
				(width 0.1)
				(type default)
			)
			(layer "F.Fab")
		)
		(fp_line
			(start 0.8636 -0.4064)
			(end 1.1938 -0.4064)
			(stroke
				(width 0.1)
				(type default)
			)
			(layer "F.Fab")
		)
		(fp_line
			(start 0.8636 -0.4572)
			(end 0.8636 -0.4064)
			(stroke
				(width 0.1)
				(type default)
			)
			(layer "F.Fab")
		)
		(fp_line
			(start -0.8636 0.4572)
			(end -0.8636 0.4064)
			(stroke
				(width 0.1)
				(type default)
			)
			(layer "F.Fab")
		)
		(fp_line
			(start -0.8636 0.4064)
			(end -1.1938 0.4064)
			(stroke
				(width 0.1)
				(type default)
			)
			(layer "F.Fab")
		)
		(fp_line
			(start -0.8636 -0.4064)
			(end -0.8636 -0.4572)
			(stroke
				(width 0.1)
				(type default)
			)
			(layer "F.Fab")
		)
		(fp_line
			(start -0.8636 -0.4572)
			(end 0.8636 -0.4572)
			(stroke
				(width 0.1)
				(type default)
			)
			(layer "F.Fab")
		)
		(fp_line
			(start -1.1938 0.4064)
			(end -1.1938 -0.4064)
			(stroke
				(width 0.1)
				(type default)
			)
			(layer "F.Fab")
		)
		(fp_line
			(start -1.1938 -0.4064)
			(end -0.8636 -0.4064)
			(stroke
				(width 0.1)
				(type default)
			)
			(layer "F.Fab")
		)
		(pad "1" smd rect
			(at -0.7366 0 90)
			(size 0.7112 0.8128)
			(layers "F.Cu" "F.Mask" "F.Paste")
			(net "P12V_OCP_AVIN_PD_2")
		)
		(pad "2" smd rect
			(at 0.7366 0 90)
			(size 0.7112 0.8128)
			(layers "F.Cu" "F.Mask" "F.Paste")
			(net "GND")
		)
	)
)
